FILE_TYPE = CONNECTIVITY;
{Allegro Design Entry HDL 17.2-2016 S081 (4005846) 1/11/2022}
"PAGE_NUMBER" = 154;
0"NC";
END.
